(kicad_pcb
	(version 20260206)
	(generator "pcbnew")
	(generator_version "10.0")
	(general
		(thickness 1.6)
		(legacy_teardrops no)
	)
	(paper "A4")
	(title_block
		(title "04192023_DAF0TMB3IC0_F0TG_MB_C_brd_V02_OCP.brd")
		(comment 1 "Grand Teton / footprints 7554-7561 of 8354")
	)
	(layers
		(0 "F.Cu" signal "TOP")
		(4 "In1.Cu" signal "GND")
		(6 "In2.Cu" signal "IN1")
		(8 "In3.Cu" signal "GND1")
		(10 "In4.Cu" signal "IN2")
		(12 "In5.Cu" signal "GND2")
		(14 "In6.Cu" signal "IN3")
		(16 "In7.Cu" signal "GND3")
		(18 "In8.Cu" signal "VCC")
		(20 "In9.Cu" signal "VCC1")
		(22 "In10.Cu" signal "GND4")
		(24 "In11.Cu" signal "IN4")
		(26 "In12.Cu" signal "GND5")
		(28 "In13.Cu" signal "IN5")
		(30 "In14.Cu" signal "GND6")
		(32 "In15.Cu" signal "IN6")
		(34 "In16.Cu" signal "GND7")
		(2 "B.Cu" signal "BOTTOM")
		(9 "F.Adhes" user "F.Adhesive")
		(11 "B.Adhes" user "B.Adhesive")
		(13 "F.Paste" user "Package Geometry/Pastemask Top")
		(15 "B.Paste" user "Package Geometry/Pastemask Bottom")
		(5 "F.SilkS" user "Ref Des/Silkscreen Top")
		(7 "B.SilkS" user "Ref Des/Silkscreen Bottom")
		(1 "F.Mask" user "Board Geometry/Soldermask Top")
		(3 "B.Mask" user "Board Geometry/Soldermask Bottom")
		(17 "Dwgs.User" user "User.Drawings")
		(19 "Cmts.User" user "User.Comments")
		(21 "Eco1.User" user "User.Eco1")
		(23 "Eco2.User" user "User.Eco2")
		(25 "Edge.Cuts" user "Board Geometry/Outline")
		(27 "Margin" user)
		(31 "F.CrtYd" user "Package Geometry/Place Bound Top")
		(29 "B.CrtYd" user "Package Geometry/Place Bound Bottom")
		(35 "F.Fab" user "Ref Des/Assembly Top")
		(33 "B.Fab" user "Ref Des/Assembly Bottom")
	)
	(footprint ""
		(layer "B.Cu")
		(at 130.657092 -49.502822 -90)
		(property "Reference" "R6066"
			(at 0 0 90)
			(layer "B.SilkS")
			(hide yes)
			(effects
				(font
					(size 1.27 1.27)
				)
				(justify mirror)
			)
		)
		(property "Value" ""
			(at 0 0 90)
			(layer "B.Fab")
			(effects
				(font
					(size 1.27 1.27)
				)
				(justify mirror)
			)
		)
		(duplicate_pad_numbers_are_jumpers no)
		(fp_line
			(start -0.7874 0.4064)
			(end 0.7874 0.4064)
			(stroke
				(width 0.1524)
				(type default)
			)
			(layer "B.SilkS")
		)
		(fp_line
			(start 0.7874 0.4064)
			(end 0.7874 -0.4064)
			(stroke
				(width 0.1524)
				(type default)
			)
			(layer "B.SilkS")
		)
		(fp_line
			(start -0.7874 -0.4064)
			(end -0.7874 0.4064)
			(stroke
				(width 0.1524)
				(type default)
			)
			(layer "B.SilkS")
		)
		(fp_line
			(start 0.7874 -0.4064)
			(end -0.7874 -0.4064)
			(stroke
				(width 0.1524)
				(type default)
			)
			(layer "B.SilkS")
		)
		(fp_line
			(start -0.67945 0.3048)
			(end -0.120396 0.3048)
			(stroke
				(width 0.1)
				(type default)
			)
			(layer "B.Fab")
		)
		(fp_line
			(start -0.120396 0.3048)
			(end -0.120396 0.2794)
			(stroke
				(width 0.1)
				(type default)
			)
			(layer "B.Fab")
		)
		(fp_line
			(start 0.12065 0.3048)
			(end 0.67945 0.3048)
			(stroke
				(width 0.1)
				(type default)
			)
			(layer "B.Fab")
		)
		(fp_line
			(start 0.67945 0.3048)
			(end 0.67945 -0.305054)
			(stroke
				(width 0.1)
				(type default)
			)
			(layer "B.Fab")
		)
		(fp_line
			(start -0.120396 0.2794)
			(end 0.12065 0.2794)
			(stroke
				(width 0.1)
				(type default)
			)
			(layer "B.Fab")
		)
		(fp_line
			(start 0.12065 0.2794)
			(end 0.12065 0.3048)
			(stroke
				(width 0.1)
				(type default)
			)
			(layer "B.Fab")
		)
		(fp_line
			(start -0.12065 -0.2794)
			(end -0.12065 -0.3048)
			(stroke
				(width 0.1)
				(type default)
			)
			(layer "B.Fab")
		)
		(fp_line
			(start 0.12065 -0.2794)
			(end -0.12065 -0.2794)
			(stroke
				(width 0.1)
				(type default)
			)
			(layer "B.Fab")
		)
		(fp_line
			(start -0.67945 -0.3048)
			(end -0.67945 0.3048)
			(stroke
				(width 0.1)
				(type default)
			)
			(layer "B.Fab")
		)
		(fp_line
			(start -0.12065 -0.3048)
			(end -0.67945 -0.3048)
			(stroke
				(width 0.1)
				(type default)
			)
			(layer "B.Fab")
		)
		(fp_line
			(start 0.12065 -0.305054)
			(end 0.12065 -0.2794)
			(stroke
				(width 0.1)
				(type default)
			)
			(layer "B.Fab")
		)
		(fp_line
			(start 0.67945 -0.305054)
			(end 0.12065 -0.305054)
			(stroke
				(width 0.1)
				(type default)
			)
			(layer "B.Fab")
		)
		(pad "1" smd rect
			(at 0.40005 0 270)
			(size 0.4572 0.508)
			(layers "B.Cu" "B.Mask" "B.Paste")
			(net "JTAG_SCM_TDI_R")
		)
		(pad "2" smd rect
			(at -0.40005 0 270)
			(size 0.4572 0.508)
			(layers "B.Cu" "B.Mask" "B.Paste")
			(net "JTAG_SCM_TDI")
		)
	)
	(footprint ""
		(layer "B.Cu")
		(at 238.633 -336.169 180)
		(property "Reference" "R803"
			(at 0 0 0)
			(layer "B.SilkS")
			(hide yes)
			(effects
				(font
					(size 1.27 1.27)
				)
				(justify mirror)
			)
		)
		(property "Value" ""
			(at 0 0 0)
			(layer "B.Fab")
			(effects
				(font
					(size 1.27 1.27)
				)
				(justify mirror)
			)
		)
		(duplicate_pad_numbers_are_jumpers no)
		(fp_line
			(start 0.32512 0.175006)
			(end 0.32512 -0.175006)
			(stroke
				(width 0.1)
				(type default)
			)
			(layer "B.Fab")
		)
		(fp_line
			(start 0.32512 -0.175006)
			(end -0.32512 -0.175006)
			(stroke
				(width 0.1)
				(type default)
			)
			(layer "B.Fab")
		)
		(fp_line
			(start -0.32512 0.175006)
			(end 0.32512 0.175006)
			(stroke
				(width 0.1)
				(type default)
			)
			(layer "B.Fab")
		)
		(fp_line
			(start -0.32512 -0.175006)
			(end -0.32512 0.175006)
			(stroke
				(width 0.1)
				(type default)
			)
			(layer "B.Fab")
		)
		(pad "1" smd rect
			(at 0.2667 0)
			(size 0.3048 0.381)
			(layers "B.Cu" "B.Mask" "B.Paste")
			(net "SMB_RT_CPU1_P1_ROM_MUX_2D_SDA")
		)
		(pad "2" smd rect
			(at -0.2667 0 180)
			(size 0.3048 0.381)
			(layers "B.Cu" "B.Mask" "B.Paste")
			(net "SMB_RT_CPU1_P1_ROM_MUX_2D_R_SDA")
		)
	)
	(footprint ""
		(layer "B.Cu")
		(at 428.309278 -353.80549 -90)
		(property "Reference" "PR138"
			(at 0 0 90)
			(layer "B.SilkS")
			(hide yes)
			(effects
				(font
					(size 1.27 1.27)
				)
				(justify mirror)
			)
		)
		(property "Value" ""
			(at 0 0 90)
			(layer "B.Fab")
			(effects
				(font
					(size 1.27 1.27)
				)
				(justify mirror)
			)
		)
		(duplicate_pad_numbers_are_jumpers no)
		(fp_line
			(start -0.7874 0.4064)
			(end 0.7874 0.4064)
			(stroke
				(width 0.1524)
				(type default)
			)
			(layer "B.SilkS")
		)
		(fp_line
			(start 0.7874 0.4064)
			(end 0.7874 -0.4064)
			(stroke
				(width 0.1524)
				(type default)
			)
			(layer "B.SilkS")
		)
		(fp_line
			(start -0.7874 -0.4064)
			(end -0.7874 0.4064)
			(stroke
				(width 0.1524)
				(type default)
			)
			(layer "B.SilkS")
		)
		(fp_line
			(start 0.7874 -0.4064)
			(end -0.7874 -0.4064)
			(stroke
				(width 0.1524)
				(type default)
			)
			(layer "B.SilkS")
		)
		(fp_line
			(start -0.67945 0.3048)
			(end -0.120396 0.3048)
			(stroke
				(width 0.1)
				(type default)
			)
			(layer "B.Fab")
		)
		(fp_line
			(start -0.120396 0.3048)
			(end -0.120396 0.2794)
			(stroke
				(width 0.1)
				(type default)
			)
			(layer "B.Fab")
		)
		(fp_line
			(start 0.12065 0.3048)
			(end 0.67945 0.3048)
			(stroke
				(width 0.1)
				(type default)
			)
			(layer "B.Fab")
		)
		(fp_line
			(start 0.67945 0.3048)
			(end 0.67945 -0.305054)
			(stroke
				(width 0.1)
				(type default)
			)
			(layer "B.Fab")
		)
		(fp_line
			(start -0.120396 0.2794)
			(end 0.12065 0.2794)
			(stroke
				(width 0.1)
				(type default)
			)
			(layer "B.Fab")
		)
		(fp_line
			(start 0.12065 0.2794)
			(end 0.12065 0.3048)
			(stroke
				(width 0.1)
				(type default)
			)
			(layer "B.Fab")
		)
		(fp_line
			(start -0.12065 -0.2794)
			(end -0.12065 -0.3048)
			(stroke
				(width 0.1)
				(type default)
			)
			(layer "B.Fab")
		)
		(fp_line
			(start 0.12065 -0.2794)
			(end -0.12065 -0.2794)
			(stroke
				(width 0.1)
				(type default)
			)
			(layer "B.Fab")
		)
		(fp_line
			(start -0.67945 -0.3048)
			(end -0.67945 0.3048)
			(stroke
				(width 0.1)
				(type default)
			)
			(layer "B.Fab")
		)
		(fp_line
			(start -0.12065 -0.3048)
			(end -0.67945 -0.3048)
			(stroke
				(width 0.1)
				(type default)
			)
			(layer "B.Fab")
		)
		(fp_line
			(start 0.12065 -0.305054)
			(end 0.12065 -0.2794)
			(stroke
				(width 0.1)
				(type default)
			)
			(layer "B.Fab")
		)
		(fp_line
			(start 0.67945 -0.305054)
			(end 0.12065 -0.305054)
			(stroke
				(width 0.1)
				(type default)
			)
			(layer "B.Fab")
		)
		(pad "1" smd circle
			(at 0.40005 0 90)
			(size 0 0)
			(layers "B.Cu" "B.Mask" "B.Paste")
			(net "PVDD11_S3_P0_VOS2")
		)
		(pad "2" smd circle
			(at -0.40005 0 90)
			(size 0 0)
			(layers "B.Cu" "B.Mask" "B.Paste")
			(net "PVDD11_S3_P0")
		)
	)
	(footprint ""
		(layer "B.Cu")
		(at 200.952608 -122.769376 180)
		(property "Reference" "R3484"
			(at 0 0 0)
			(layer "B.SilkS")
			(hide yes)
			(effects
				(font
					(size 1.27 1.27)
				)
				(justify mirror)
			)
		)
		(property "Value" ""
			(at 0 0 0)
			(layer "B.Fab")
			(effects
				(font
					(size 1.27 1.27)
				)
				(justify mirror)
			)
		)
		(duplicate_pad_numbers_are_jumpers no)
		(fp_line
			(start 0.7874 0.4064)
			(end 0.7874 -0.4064)
			(stroke
				(width 0.1524)
				(type default)
			)
			(layer "B.SilkS")
		)
		(fp_line
			(start 0.7874 -0.4064)
			(end -0.7874 -0.4064)
			(stroke
				(width 0.1524)
				(type default)
			)
			(layer "B.SilkS")
		)
		(fp_line
			(start -0.7874 0.4064)
			(end 0.7874 0.4064)
			(stroke
				(width 0.1524)
				(type default)
			)
			(layer "B.SilkS")
		)
		(fp_line
			(start -0.7874 -0.4064)
			(end -0.7874 0.4064)
			(stroke
				(width 0.1524)
				(type default)
			)
			(layer "B.SilkS")
		)
		(fp_line
			(start 0.67945 0.3048)
			(end 0.67945 -0.305054)
			(stroke
				(width 0.1)
				(type default)
			)
			(layer "B.Fab")
		)
		(fp_line
			(start 0.67945 -0.305054)
			(end 0.12065 -0.305054)
			(stroke
				(width 0.1)
				(type default)
			)
			(layer "B.Fab")
		)
		(fp_line
			(start 0.12065 0.3048)
			(end 0.67945 0.3048)
			(stroke
				(width 0.1)
				(type default)
			)
			(layer "B.Fab")
		)
		(fp_line
			(start 0.12065 0.2794)
			(end 0.12065 0.3048)
			(stroke
				(width 0.1)
				(type default)
			)
			(layer "B.Fab")
		)
		(fp_line
			(start 0.12065 -0.2794)
			(end -0.12065 -0.2794)
			(stroke
				(width 0.1)
				(type default)
			)
			(layer "B.Fab")
		)
		(fp_line
			(start 0.12065 -0.305054)
			(end 0.12065 -0.2794)
			(stroke
				(width 0.1)
				(type default)
			)
			(layer "B.Fab")
		)
		(fp_line
			(start -0.120396 0.3048)
			(end -0.120396 0.2794)
			(stroke
				(width 0.1)
				(type default)
			)
			(layer "B.Fab")
		)
		(fp_line
			(start -0.120396 0.2794)
			(end 0.12065 0.2794)
			(stroke
				(width 0.1)
				(type default)
			)
			(layer "B.Fab")
		)
		(fp_line
			(start -0.12065 -0.2794)
			(end -0.12065 -0.3048)
			(stroke
				(width 0.1)
				(type default)
			)
			(layer "B.Fab")
		)
		(fp_line
			(start -0.12065 -0.3048)
			(end -0.67945 -0.3048)
			(stroke
				(width 0.1)
				(type default)
			)
			(layer "B.Fab")
		)
		(fp_line
			(start -0.67945 0.3048)
			(end -0.120396 0.3048)
			(stroke
				(width 0.1)
				(type default)
			)
			(layer "B.Fab")
		)
		(fp_line
			(start -0.67945 -0.3048)
			(end -0.67945 0.3048)
			(stroke
				(width 0.1)
				(type default)
			)
			(layer "B.Fab")
		)
		(pad "1" smd circle
			(at 0.40005 0)
			(size 0 0)
			(layers "B.Cu" "B.Mask" "B.Paste")
			(net "GPU_FPGA_OVERT_ISO_R_N")
		)
		(pad "2" smd circle
			(at -0.40005 0)
			(size 0 0)
			(layers "B.Cu" "B.Mask" "B.Paste")
			(net "GPU_FPGA_OVERT_ISO_N")
		)
	)
	(footprint ""
		(layer "B.Cu")
		(at 239.903 -336.169)
		(property "Reference" "R1393"
			(at 0 0 0)
			(layer "B.SilkS")
			(hide yes)
			(effects
				(font
					(size 1.27 1.27)
				)
				(justify mirror)
			)
		)
		(property "Value" ""
			(at 0 0 0)
			(layer "B.Fab")
			(effects
				(font
					(size 1.27 1.27)
				)
				(justify mirror)
			)
		)
		(duplicate_pad_numbers_are_jumpers no)
		(fp_line
			(start -0.32512 -0.175006)
			(end -0.32512 0.175006)
			(stroke
				(width 0.1)
				(type default)
			)
			(layer "B.Fab")
		)
		(fp_line
			(start -0.32512 0.175006)
			(end 0.32512 0.175006)
			(stroke
				(width 0.1)
				(type default)
			)
			(layer "B.Fab")
		)
		(fp_line
			(start 0.32512 -0.175006)
			(end -0.32512 -0.175006)
			(stroke
				(width 0.1)
				(type default)
			)
			(layer "B.Fab")
		)
		(fp_line
			(start 0.32512 0.175006)
			(end 0.32512 -0.175006)
			(stroke
				(width 0.1)
				(type default)
			)
			(layer "B.Fab")
		)
		(pad "1" smd rect
			(at 0.2667 0 180)
			(size 0.3048 0.381)
			(layers "B.Cu" "B.Mask" "B.Paste")
			(net "P1V8_CPU1_RT_1D")
		)
		(pad "2" smd rect
			(at -0.2667 0)
			(size 0.3048 0.381)
			(layers "B.Cu" "B.Mask" "B.Paste")
			(net "SMB_RT_CPU1_P1_ROM_MUX_2D_R_SDA")
		)
	)
	(footprint ""
		(layer "B.Cu")
		(at 284.386528 -339.910928 -90)
		(property "Reference" "PC165"
			(at 9.490456 0.924814 270)
			(unlocked yes)
			(layer "B.SilkS")
			(effects
				(font
					(size 0.7874 0.5842)
					(thickness 0.1524)
				)
				(justify left mirror)
			)
		)
		(property "Value" ""
			(at 0 0 90)
			(layer "B.Fab")
			(effects
				(font
					(size 1.27 1.27)
				)
				(justify mirror)
			)
		)
		(duplicate_pad_numbers_are_jumpers no)
		(fp_line
			(start -4.533392 2.249932)
			(end 4.533392 2.249932)
			(stroke
				(width 0.1524)
				(type default)
			)
			(layer "B.SilkS")
		)
		(fp_line
			(start 4.533392 2.249932)
			(end 4.533392 -2.249932)
			(stroke
				(width 0.1524)
				(type default)
			)
			(layer "B.SilkS")
		)
		(fp_line
			(start -4.533392 -2.249932)
			(end -4.533392 2.249932)
			(stroke
				(width 0.1524)
				(type default)
			)
			(layer "B.SilkS")
		)
		(fp_line
			(start 4.533392 -2.249932)
			(end -4.533392 -2.249932)
			(stroke
				(width 0.1524)
				(type default)
			)
			(layer "B.SilkS")
		)
		(fp_rect
			(start 5.39242 2.326132)
			(end 4.533392 -2.326132)
			(stroke
				(width 0)
				(type default)
			)
			(fill yes)
			(layer "B.SilkS")
		)
		(fp_line
			(start -3.750056 2.249932)
			(end 3.750056 2.249932)
			(stroke
				(width 0.1)
				(type default)
			)
			(layer "B.Fab")
		)
		(fp_line
			(start 3.750056 2.249932)
			(end 3.750056 -2.249932)
			(stroke
				(width 0.1)
				(type default)
			)
			(layer "B.Fab")
		)
		(fp_line
			(start -3.750056 -2.249932)
			(end -3.750056 2.249932)
			(stroke
				(width 0.1)
				(type default)
			)
			(layer "B.Fab")
		)
		(fp_line
			(start 3.750056 -2.249932)
			(end -3.750056 -2.249932)
			(stroke
				(width 0.1)
				(type default)
			)
			(layer "B.Fab")
		)
		(fp_text user "-"
			(at -4.699254 0.960374 270)
			(unlocked yes)
			(layer "B.SilkS")
			(effects
				(font
					(size 1.905 1.4224)
					(thickness 0.1524)
				)
				(justify left mirror)
			)
		)
		(fp_text user "+"
			(at 6.322314 0.786384 180)
			(unlocked yes)
			(layer "B.SilkS")
			(effects
				(font
					(size 1.905 1.4224)
					(thickness 0.1524)
				)
				(justify left mirror)
			)
		)
		(fp_text user "+"
			(at 6.322314 0.786384 180)
			(unlocked yes)
			(layer "B.Fab")
			(effects
				(font
					(size 1.905 1.4224)
					(thickness 0.1524)
				)
				(justify left mirror)
			)
		)
		(fp_text user "-"
			(at -4.8514 -0.14605 270)
			(unlocked yes)
			(layer "B.Fab")
			(effects
				(font
					(size 1.905 1.4224)
					(thickness 0.1524)
				)
				(justify left mirror)
			)
		)
		(pad "1" smd rect
			(at 3.199892 0 90)
			(size 2.413 2.8194)
			(layers "B.Cu" "B.Mask" "B.Paste")
			(net "PVDDIO_P0")
		)
		(pad "2" smd rect
			(at -3.199892 0 90)
			(size 2.413 2.8194)
			(layers "B.Cu" "B.Mask" "B.Paste")
			(net "GND")
		)
	)
	(footprint ""
		(layer "B.Cu")
		(at 380.078488 -395.148562 90)
		(property "Reference" "C1003"
			(at 0 0 90)
			(layer "B.SilkS")
			(hide yes)
			(effects
				(font
					(size 1.27 1.27)
				)
				(justify mirror)
			)
		)
		(property "Value" ""
			(at 0 0 90)
			(layer "B.Fab")
			(effects
				(font
					(size 1.27 1.27)
				)
				(justify mirror)
			)
		)
		(duplicate_pad_numbers_are_jumpers no)
		(fp_line
			(start 0.299974 -0.150114)
			(end -0.299974 -0.150114)
			(stroke
				(width 0.1)
				(type default)
			)
			(layer "B.Fab")
		)
		(fp_line
			(start -0.299974 -0.150114)
			(end -0.299974 0.150114)
			(stroke
				(width 0.1)
				(type default)
			)
			(layer "B.Fab")
		)
		(fp_line
			(start 0.299974 0.150114)
			(end 0.299974 -0.150114)
			(stroke
				(width 0.1)
				(type default)
			)
			(layer "B.Fab")
		)
		(fp_line
			(start -0.299974 0.150114)
			(end 0.299974 0.150114)
			(stroke
				(width 0.1)
				(type default)
			)
			(layer "B.Fab")
		)
		(pad "1" smd rect
			(at 0.2667 0 270)
			(size 0.3048 0.381)
			(layers "B.Cu" "B.Mask" "B.Paste")
			(net "P1V8_CPU0_RT3_1A")
		)
		(pad "2" smd rect
			(at -0.2667 0 270)
			(size 0.3048 0.381)
			(layers "B.Cu" "B.Mask" "B.Paste")
			(net "GND")
		)
	)
	(footprint ""
		(layer "B.Cu")
		(at 74.5236 -384.66268 180)
		(property "Reference" "R786"
			(at 0 0 0)
			(layer "B.SilkS")
			(hide yes)
			(effects
				(font
					(size 1.27 1.27)
				)
				(justify mirror)
			)
		)
		(property "Value" ""
			(at 0 0 0)
			(layer "B.Fab")
			(effects
				(font
					(size 1.27 1.27)
				)
				(justify mirror)
			)
		)
		(duplicate_pad_numbers_are_jumpers no)
		(fp_line
			(start 0.32512 0.175006)
			(end 0.32512 -0.175006)
			(stroke
				(width 0.1)
				(type default)
			)
			(layer "B.Fab")
		)
		(fp_line
			(start 0.32512 -0.175006)
			(end -0.32512 -0.175006)
			(stroke
				(width 0.1)
				(type default)
			)
			(layer "B.Fab")
		)
		(fp_line
			(start -0.32512 0.175006)
			(end 0.32512 0.175006)
			(stroke
				(width 0.1)
				(type default)
			)
			(layer "B.Fab")
		)
		(fp_line
			(start -0.32512 -0.175006)
			(end -0.32512 0.175006)
			(stroke
				(width 0.1)
				(type default)
			)
			(layer "B.Fab")
		)
		(pad "1" smd rect
			(at 0.2667 0)
			(size 0.3048 0.381)
			(layers "B.Cu" "B.Mask" "B.Paste")
			(net "P1V8_CPU1_RT_1D")
		)
		(pad "2" smd rect
			(at -0.2667 0 180)
			(size 0.3048 0.381)
			(layers "B.Cu" "B.Mask" "B.Paste")
			(net "TEST1_RT_CPU1_P1")
		)
	)
)
